# T6G (Grand Teton) — schematic netlist excerpt (pin names and nets, part order shuffled) for the footprints in the layout excerpt that follows; sources: Cadence DE-HDL packaged netlist, KiCad conversion of 04192023_DAF0TMB3IC0_F0TG_MB_C_brd_V02_OCP.brd

R6253  Q_RES  33.2 1% CHIP  pkg 0402LF  page 271 : A = SMB_LM75_0_3V3AUX_SDA ; B = SMB_HSC_TYPE_ADC_SDA
R6258  Q_RES  4.7K 5% EMPTY  pkg 0402LF  page 178 : A = P3V3_AUX ; B = USB_HUB2_TI_PWRCTL2_MRP_VDD12

(kicad_pcb
	(version 20260206)
	(generator "pcbnew")
	(generator_version "10.0")
	(general
		(thickness 1.6)
		(legacy_teardrops no)
	)
	(paper "A4")
	(title_block
		(title "04192023_DAF0TMB3IC0_F0TG_MB_C_brd_V02_OCP.brd")
		(comment 1 "Grand Teton / footprints 3822-3823 of 8354")
	)
	(layers
		(0 "F.Cu" signal "TOP")
		(4 "In1.Cu" signal "GND")
		(6 "In2.Cu" signal "IN1")
		(8 "In3.Cu" signal "GND1")
		(10 "In4.Cu" signal "IN2")
		(12 "In5.Cu" signal "GND2")
		(14 "In6.Cu" signal "IN3")
		(16 "In7.Cu" signal "GND3")
		(18 "In8.Cu" signal "VCC")
		(20 "In9.Cu" signal "VCC1")
		(22 "In10.Cu" signal "GND4")
		(24 "In11.Cu" signal "IN4")
		(26 "In12.Cu" signal "GND5")
		(28 "In13.Cu" signal "IN5")
		(30 "In14.Cu" signal "GND6")
		(32 "In15.Cu" signal "IN6")
		(34 "In16.Cu" signal "GND7")
		(2 "B.Cu" signal "BOTTOM")
		(9 "F.Adhes" user "F.Adhesive")
		(11 "B.Adhes" user "B.Adhesive")
		(13 "F.Paste" user "Package Geometry/Pastemask Top")
		(15 "B.Paste" user "Package Geometry/Pastemask Bottom")
		(5 "F.SilkS" user "Ref Des/Silkscreen Top")
		(7 "B.SilkS" user "Ref Des/Silkscreen Bottom")
		(1 "F.Mask" user "Board Geometry/Soldermask Top")
		(3 "B.Mask" user "Board Geometry/Soldermask Bottom")
		(17 "Dwgs.User" user "User.Drawings")
		(19 "Cmts.User" user "User.Comments")
		(21 "Eco1.User" user "User.Eco1")
		(23 "Eco2.User" user "User.Eco2")
		(25 "Edge.Cuts" user "Board Geometry/Outline")
		(27 "Margin" user)
		(31 "F.CrtYd" user "Package Geometry/Place Bound Top")
		(29 "B.CrtYd" user "Package Geometry/Place Bound Bottom")
		(35 "F.Fab" user "Ref Des/Assembly Top")
		(33 "B.Fab" user "Ref Des/Assembly Bottom")
	)
	(footprint ""
		(layer "F.Cu")
		(at 365.887 -411.226 -90)
		(property "Reference" "R6253"
			(at 0 0 270)
			(layer "F.SilkS")
			(hide yes)
			(effects
				(font
					(size 1.27 1.27)
				)
			)
		)
		(property "Value" ""
			(at 0 0 270)
			(layer "F.Fab")
			(effects
				(font
					(size 1.27 1.27)
				)
			)
		)
		(duplicate_pad_numbers_are_jumpers no)
		(fp_line
			(start -0.7874 0.4064)
			(end -0.7874 -0.4064)
			(stroke
				(width 0.1524)
				(type default)
			)
			(layer "F.SilkS")
		)
		(fp_line
			(start 0.7874 0.4064)
			(end -0.7874 0.4064)
			(stroke
				(width 0.1524)
				(type default)
			)
			(layer "F.SilkS")
		)
		(fp_line
			(start -0.7874 -0.4064)
			(end 0.7874 -0.4064)
			(stroke
				(width 0.1524)
				(type default)
			)
			(layer "F.SilkS")
		)
		(fp_line
			(start 0.7874 -0.4064)
			(end 0.7874 0.4064)
			(stroke
				(width 0.1524)
				(type default)
			)
			(layer "F.SilkS")
		)
		(fp_line
			(start -0.67945 0.3048)
			(end -0.67945 -0.305054)
			(stroke
				(width 0.1)
				(type default)
			)
			(layer "F.Fab")
		)
		(fp_line
			(start -0.12065 0.3048)
			(end -0.67945 0.3048)
			(stroke
				(width 0.1)
				(type default)
			)
			(layer "F.Fab")
		)
		(fp_line
			(start 0.120396 0.3048)
			(end 0.120396 0.2794)
			(stroke
				(width 0.1)
				(type default)
			)
			(layer "F.Fab")
		)
		(fp_line
			(start 0.67945 0.3048)
			(end 0.120396 0.3048)
			(stroke
				(width 0.1)
				(type default)
			)
			(layer "F.Fab")
		)
		(fp_line
			(start -0.12065 0.2794)
			(end -0.12065 0.3048)
			(stroke
				(width 0.1)
				(type default)
			)
			(layer "F.Fab")
		)
		(fp_line
			(start 0.120396 0.2794)
			(end -0.12065 0.2794)
			(stroke
				(width 0.1)
				(type default)
			)
			(layer "F.Fab")
		)
		(fp_line
			(start -0.12065 -0.2794)
			(end 0.12065 -0.2794)
			(stroke
				(width 0.1)
				(type default)
			)
			(layer "F.Fab")
		)
		(fp_line
			(start 0.12065 -0.2794)
			(end 0.12065 -0.3048)
			(stroke
				(width 0.1)
				(type default)
			)
			(layer "F.Fab")
		)
		(fp_line
			(start 0.12065 -0.3048)
			(end 0.67945 -0.3048)
			(stroke
				(width 0.1)
				(type default)
			)
			(layer "F.Fab")
		)
		(fp_line
			(start 0.67945 -0.3048)
			(end 0.67945 0.3048)
			(stroke
				(width 0.1)
				(type default)
			)
			(layer "F.Fab")
		)
		(fp_line
			(start -0.67945 -0.305054)
			(end -0.12065 -0.305054)
			(stroke
				(width 0.1)
				(type default)
			)
			(layer "F.Fab")
		)
		(fp_line
			(start -0.12065 -0.305054)
			(end -0.12065 -0.2794)
			(stroke
				(width 0.1)
				(type default)
			)
			(layer "F.Fab")
		)
		(pad "1" smd circle
			(at -0.40005 0 270)
			(size 0 0)
			(layers "F.Cu" "F.Mask" "F.Paste")
			(net "SMB_LM75_0_3V3AUX_SDA")
		)
		(pad "2" smd circle
			(at 0.40005 0 270)
			(size 0 0)
			(layers "F.Cu" "F.Mask" "F.Paste")
			(net "SMB_HSC_TYPE_ADC_SDA")
		)
	)
	(footprint ""
		(layer "F.Cu")
		(at 121.411238 -41.17975 -90)
		(property "Reference" "R6258"
			(at 0 0 270)
			(layer "F.SilkS")
			(hide yes)
			(effects
				(font
					(size 1.27 1.27)
				)
			)
		)
		(property "Value" ""
			(at 0 0 270)
			(layer "F.Fab")
			(effects
				(font
					(size 1.27 1.27)
				)
			)
		)
		(duplicate_pad_numbers_are_jumpers no)
		(fp_line
			(start -0.7874 0.4064)
			(end -0.7874 -0.4064)
			(stroke
				(width 0.1524)
				(type default)
			)
			(layer "F.SilkS")
		)
		(fp_line
			(start 0.7874 0.4064)
			(end -0.7874 0.4064)
			(stroke
				(width 0.1524)
				(type default)
			)
			(layer "F.SilkS")
		)
		(fp_line
			(start -0.7874 -0.4064)
			(end 0.7874 -0.4064)
			(stroke
				(width 0.1524)
				(type default)
			)
			(layer "F.SilkS")
		)
		(fp_line
			(start 0.7874 -0.4064)
			(end 0.7874 0.4064)
			(stroke
				(width 0.1524)
				(type default)
			)
			(layer "F.SilkS")
		)
		(fp_line
			(start -0.67945 0.3048)
			(end -0.67945 -0.305054)
			(stroke
				(width 0.1)
				(type default)
			)
			(layer "F.Fab")
		)
		(fp_line
			(start -0.12065 0.3048)
			(end -0.67945 0.3048)
			(stroke
				(width 0.1)
				(type default)
			)
			(layer "F.Fab")
		)
		(fp_line
			(start 0.120396 0.3048)
			(end 0.120396 0.2794)
			(stroke
				(width 0.1)
				(type default)
			)
			(layer "F.Fab")
		)
		(fp_line
			(start 0.67945 0.3048)
			(end 0.120396 0.3048)
			(stroke
				(width 0.1)
				(type default)
			)
			(layer "F.Fab")
		)
		(fp_line
			(start -0.12065 0.2794)
			(end -0.12065 0.3048)
			(stroke
				(width 0.1)
				(type default)
			)
			(layer "F.Fab")
		)
		(fp_line
			(start 0.120396 0.2794)
			(end -0.12065 0.2794)
			(stroke
				(width 0.1)
				(type default)
			)
			(layer "F.Fab")
		)
		(fp_line
			(start -0.12065 -0.2794)
			(end 0.12065 -0.2794)
			(stroke
				(width 0.1)
				(type default)
			)
			(layer "F.Fab")
		)
		(fp_line
			(start 0.12065 -0.2794)
			(end 0.12065 -0.3048)
			(stroke
				(width 0.1)
				(type default)
			)
			(layer "F.Fab")
		)
		(fp_line
			(start 0.12065 -0.3048)
			(end 0.67945 -0.3048)
			(stroke
				(width 0.1)
				(type default)
			)
			(layer "F.Fab")
		)
		(fp_line
			(start 0.67945 -0.3048)
			(end 0.67945 0.3048)
			(stroke
				(width 0.1)
				(type default)
			)
			(layer "F.Fab")
		)
		(fp_line
			(start -0.67945 -0.305054)
			(end -0.12065 -0.305054)
			(stroke
				(width 0.1)
				(type default)
			)
			(layer "F.Fab")
		)
		(fp_line
			(start -0.12065 -0.305054)
			(end -0.12065 -0.2794)
			(stroke
				(width 0.1)
				(type default)
			)
			(layer "F.Fab")
		)
		(pad "1" smd circle
			(at -0.40005 0 270)
			(size 0 0)
			(layers "F.Cu" "F.Mask" "F.Paste")
			(net "P3V3_AUX")
		)
		(pad "2" smd circle
			(at 0.40005 0 270)
			(size 0 0)
			(layers "F.Cu" "F.Mask" "F.Paste")
			(net "USB_HUB2_TI_PWRCTL2_MRP_VDD12")
		)
	)
)
